(kicad_pcb
	(version 20260206)
	(generator "pcbnew")
	(generator_version "10.0")
	(general
		(thickness 1.6)
		(legacy_teardrops no)
	)
	(paper "A4")
	(title_block
		(title "01162023_DA0F0TEBIF0_F0T_Expander_BD_F_brd_V02_OCP.brd")
		(comment 1 "Grand Teton / footprints 7912-7918 of 9728")
	)
	(layers
		(0 "F.Cu" signal "TOP")
		(4 "In1.Cu" signal "GND")
		(6 "In2.Cu" signal "VCC")
		(8 "In3.Cu" signal "VCC1")
		(10 "In4.Cu" signal "GND1")
		(12 "In5.Cu" signal "IN1")
		(14 "In6.Cu" signal "GND2")
		(16 "In7.Cu" signal "IN2")
		(18 "In8.Cu" signal "GND3")
		(20 "In9.Cu" signal "IN3")
		(22 "In10.Cu" signal "GND4")
		(24 "In11.Cu" signal "IN4")
		(26 "In12.Cu" signal "GND5")
		(28 "In13.Cu" signal "IN5")
		(30 "In14.Cu" signal "GND6")
		(32 "In15.Cu" signal "IN6")
		(34 "In16.Cu" signal "GND7")
		(2 "B.Cu" signal "BOTTOM")
		(9 "F.Adhes" user "F.Adhesive")
		(11 "B.Adhes" user "B.Adhesive")
		(13 "F.Paste" user "Package Geometry/Pastemask Top")
		(15 "B.Paste" user "Package Geometry/Pastemask Bottom")
		(5 "F.SilkS" user "Ref Des/Silkscreen Top")
		(7 "B.SilkS" user "Ref Des/Silkscreen Bottom")
		(1 "F.Mask" user "Board Geometry/Soldermask Top")
		(3 "B.Mask" user "Board Geometry/Soldermask Bottom")
		(17 "Dwgs.User" user "User.Drawings")
		(19 "Cmts.User" user "User.Comments")
		(21 "Eco1.User" user "User.Eco1")
		(23 "Eco2.User" user "User.Eco2")
		(25 "Edge.Cuts" user "Board Geometry/Outline")
		(27 "Margin" user)
		(31 "F.CrtYd" user "Package Geometry/Place Bound Top")
		(29 "B.CrtYd" user "Package Geometry/Place Bound Bottom")
		(35 "F.Fab" user "Ref Des/Assembly Top")
		(33 "B.Fab" user "Ref Des/Assembly Bottom")
	)
	(footprint ""
		(layer "B.Cu")
		(at 116.128292 -303.141634 180)
		(property "Reference" "PR76"
			(at 0 0 0)
			(layer "B.SilkS")
			(hide yes)
			(effects
				(font
					(size 1.27 1.27)
				)
				(justify mirror)
			)
		)
		(property "Value" ""
			(at 0 0 0)
			(layer "B.Fab")
			(effects
				(font
					(size 1.27 1.27)
				)
				(justify mirror)
			)
		)
		(duplicate_pad_numbers_are_jumpers no)
		(fp_line
			(start 0.7874 0.4064)
			(end 0.7874 -0.4064)
			(stroke
				(width 0.1524)
				(type default)
			)
			(layer "B.SilkS")
		)
		(fp_line
			(start 0.7874 -0.4064)
			(end -0.7874 -0.4064)
			(stroke
				(width 0.1524)
				(type default)
			)
			(layer "B.SilkS")
		)
		(fp_line
			(start -0.7874 0.4064)
			(end 0.7874 0.4064)
			(stroke
				(width 0.1524)
				(type default)
			)
			(layer "B.SilkS")
		)
		(fp_line
			(start -0.7874 -0.4064)
			(end -0.7874 0.4064)
			(stroke
				(width 0.1524)
				(type default)
			)
			(layer "B.SilkS")
		)
		(fp_line
			(start 0.67945 0.3048)
			(end 0.67945 -0.305054)
			(stroke
				(width 0.1)
				(type default)
			)
			(layer "B.Fab")
		)
		(fp_line
			(start 0.67945 -0.305054)
			(end 0.12065 -0.305054)
			(stroke
				(width 0.1)
				(type default)
			)
			(layer "B.Fab")
		)
		(fp_line
			(start 0.12065 0.3048)
			(end 0.67945 0.3048)
			(stroke
				(width 0.1)
				(type default)
			)
			(layer "B.Fab")
		)
		(fp_line
			(start 0.12065 0.2794)
			(end 0.12065 0.3048)
			(stroke
				(width 0.1)
				(type default)
			)
			(layer "B.Fab")
		)
		(fp_line
			(start 0.12065 -0.2794)
			(end -0.12065 -0.2794)
			(stroke
				(width 0.1)
				(type default)
			)
			(layer "B.Fab")
		)
		(fp_line
			(start 0.12065 -0.305054)
			(end 0.12065 -0.2794)
			(stroke
				(width 0.1)
				(type default)
			)
			(layer "B.Fab")
		)
		(fp_line
			(start -0.120396 0.3048)
			(end -0.120396 0.2794)
			(stroke
				(width 0.1)
				(type default)
			)
			(layer "B.Fab")
		)
		(fp_line
			(start -0.120396 0.2794)
			(end 0.12065 0.2794)
			(stroke
				(width 0.1)
				(type default)
			)
			(layer "B.Fab")
		)
		(fp_line
			(start -0.12065 -0.2794)
			(end -0.12065 -0.3048)
			(stroke
				(width 0.1)
				(type default)
			)
			(layer "B.Fab")
		)
		(fp_line
			(start -0.12065 -0.3048)
			(end -0.67945 -0.3048)
			(stroke
				(width 0.1)
				(type default)
			)
			(layer "B.Fab")
		)
		(fp_line
			(start -0.67945 0.3048)
			(end -0.120396 0.3048)
			(stroke
				(width 0.1)
				(type default)
			)
			(layer "B.Fab")
		)
		(fp_line
			(start -0.67945 -0.3048)
			(end -0.67945 0.3048)
			(stroke
				(width 0.1)
				(type default)
			)
			(layer "B.Fab")
		)
		(pad "1" smd circle
			(at 0.40005 0)
			(size 0 0)
			(layers "B.Cu" "B.Mask" "B.Paste")
			(net "P0V8_PEX0")
		)
		(pad "2" smd circle
			(at -0.40005 0)
			(size 0 0)
			(layers "B.Cu" "B.Mask" "B.Paste")
			(net "SH_P0V8_PEX0_VSEN0_L")
		)
	)
	(footprint ""
		(layer "B.Cu")
		(at 288.049716 -301.599854 -90)
		(property "Reference" "C1733"
			(at 0 0 90)
			(layer "B.SilkS")
			(hide yes)
			(effects
				(font
					(size 1.27 1.27)
				)
				(justify mirror)
			)
		)
		(property "Value" ""
			(at 0 0 90)
			(layer "B.Fab")
			(effects
				(font
					(size 1.27 1.27)
				)
				(justify mirror)
			)
		)
		(duplicate_pad_numbers_are_jumpers no)
		(fp_line
			(start -0.299974 0.150114)
			(end 0.299974 0.150114)
			(stroke
				(width 0.1)
				(type default)
			)
			(layer "B.Fab")
		)
		(fp_line
			(start 0.299974 0.150114)
			(end 0.299974 -0.150114)
			(stroke
				(width 0.1)
				(type default)
			)
			(layer "B.Fab")
		)
		(fp_line
			(start -0.299974 -0.150114)
			(end -0.299974 0.150114)
			(stroke
				(width 0.1)
				(type default)
			)
			(layer "B.Fab")
		)
		(fp_line
			(start 0.299974 -0.150114)
			(end -0.299974 -0.150114)
			(stroke
				(width 0.1)
				(type default)
			)
			(layer "B.Fab")
		)
		(pad "1" smd rect
			(at 0.2667 0 90)
			(size 0.3048 0.381)
			(layers "B.Cu" "B.Mask" "B.Paste")
			(net "P0V8_SERDES_VDDA_PEX2")
		)
		(pad "2" smd rect
			(at -0.2667 0 90)
			(size 0.3048 0.381)
			(layers "B.Cu" "B.Mask" "B.Paste")
			(net "GND")
		)
	)
	(footprint ""
		(layer "B.Cu")
		(at 227.067618 -220.704156 180)
		(property "Reference" "C3624"
			(at 0 0 0)
			(layer "B.SilkS")
			(hide yes)
			(effects
				(font
					(size 1.27 1.27)
				)
				(justify mirror)
			)
		)
		(property "Value" ""
			(at 0 0 0)
			(layer "B.Fab")
			(effects
				(font
					(size 1.27 1.27)
				)
				(justify mirror)
			)
		)
		(duplicate_pad_numbers_are_jumpers no)
		(fp_line
			(start 0.69215 0.2921)
			(end 0.69215 -0.2921)
			(stroke
				(width 0.1524)
				(type default)
			)
			(layer "B.SilkS")
		)
		(fp_line
			(start 0.69215 -0.2921)
			(end -0.69215 -0.2921)
			(stroke
				(width 0.1524)
				(type default)
			)
			(layer "B.SilkS")
		)
		(fp_line
			(start -0.69215 0.2921)
			(end 0.69215 0.2921)
			(stroke
				(width 0.1524)
				(type default)
			)
			(layer "B.SilkS")
		)
		(fp_line
			(start -0.69215 -0.2921)
			(end -0.69215 0.2921)
			(stroke
				(width 0.1524)
				(type default)
			)
			(layer "B.SilkS")
		)
		(fp_line
			(start 0.51435 0.2794)
			(end 0.51435 -0.2794)
			(stroke
				(width 0.1)
				(type default)
			)
			(layer "B.Fab")
		)
		(fp_line
			(start 0.51435 -0.2794)
			(end -0.51435 -0.2794)
			(stroke
				(width 0.1)
				(type default)
			)
			(layer "B.Fab")
		)
		(fp_line
			(start -0.51435 0.2794)
			(end 0.51435 0.2794)
			(stroke
				(width 0.1)
				(type default)
			)
			(layer "B.Fab")
		)
		(fp_line
			(start -0.51435 -0.2794)
			(end -0.51435 0.2794)
			(stroke
				(width 0.1)
				(type default)
			)
			(layer "B.Fab")
		)
		(pad "1" smd circle
			(at 0.40005 0)
			(size 0 0)
			(layers "B.Cu" "B.Mask" "B.Paste")
			(net "P3V3_AUX")
		)
		(pad "2" smd circle
			(at -0.40005 0)
			(size 0 0)
			(layers "B.Cu" "B.Mask" "B.Paste")
			(net "GND")
		)
		(zone
			(layer "B.Cu")
			(hatch none 0.5)
			(connect_pads
				(clearance 0)
			)
			(min_thickness 0.25)
			(keepout
				(tracks not_allowed)
				(vias allowed)
				(pads allowed)
				(copperpour not_allowed)
				(footprints allowed)
			)
			(placement
				(enabled no)
				(sheetname "")
			)
			(fill
				(thermal_gap 0.5)
				(thermal_bridge_width 0.5)
				(island_removal_mode 0)
			)
			(polygon
				(pts
					(xy 226.877118 -220.791786) (xy 226.968558 -220.849952) (xy 227.167948 -220.849952) (xy 227.258118 -220.791786)
					(xy 227.258118 -220.616526) (xy 227.167948 -220.558106) (xy 226.968558 -220.558106) (xy 226.877118 -220.616272)
				)
			)
		)
	)
	(footprint ""
		(layer "B.Cu")
		(at 170.999912 -292.099746 90)
		(property "Reference" "C1456"
			(at 0 0 90)
			(layer "B.SilkS")
			(hide yes)
			(effects
				(font
					(size 1.27 1.27)
				)
				(justify mirror)
			)
		)
		(property "Value" ""
			(at 0 0 90)
			(layer "B.Fab")
			(effects
				(font
					(size 1.27 1.27)
				)
				(justify mirror)
			)
		)
		(duplicate_pad_numbers_are_jumpers no)
		(fp_line
			(start 0.299974 -0.150114)
			(end -0.299974 -0.150114)
			(stroke
				(width 0.1)
				(type default)
			)
			(layer "B.Fab")
		)
		(fp_line
			(start -0.299974 -0.150114)
			(end -0.299974 0.150114)
			(stroke
				(width 0.1)
				(type default)
			)
			(layer "B.Fab")
		)
		(fp_line
			(start 0.299974 0.150114)
			(end 0.299974 -0.150114)
			(stroke
				(width 0.1)
				(type default)
			)
			(layer "B.Fab")
		)
		(fp_line
			(start -0.299974 0.150114)
			(end 0.299974 0.150114)
			(stroke
				(width 0.1)
				(type default)
			)
			(layer "B.Fab")
		)
		(pad "1" smd rect
			(at 0.2667 0 270)
			(size 0.3048 0.381)
			(layers "B.Cu" "B.Mask" "B.Paste")
			(net "P0V8_SERDES_VDDA_PEX1")
		)
		(pad "2" smd rect
			(at -0.2667 0 270)
			(size 0.3048 0.381)
			(layers "B.Cu" "B.Mask" "B.Paste")
			(net "GND")
		)
	)
	(footprint ""
		(layer "B.Cu")
		(at 394.42644 -139.8016 180)
		(property "Reference" "C945"
			(at 0 0 0)
			(layer "B.SilkS")
			(hide yes)
			(effects
				(font
					(size 1.27 1.27)
				)
				(justify mirror)
			)
		)
		(property "Value" ""
			(at 0 0 0)
			(layer "B.Fab")
			(effects
				(font
					(size 1.27 1.27)
				)
				(justify mirror)
			)
		)
		(duplicate_pad_numbers_are_jumpers no)
		(fp_line
			(start 0.7874 0.4064)
			(end 0.7874 -0.4064)
			(stroke
				(width 0.1524)
				(type default)
			)
			(layer "B.SilkS")
		)
		(fp_line
			(start 0.7874 -0.4064)
			(end -0.7874 -0.4064)
			(stroke
				(width 0.1524)
				(type default)
			)
			(layer "B.SilkS")
		)
		(fp_line
			(start -0.7874 0.4064)
			(end 0.7874 0.4064)
			(stroke
				(width 0.1524)
				(type default)
			)
			(layer "B.SilkS")
		)
		(fp_line
			(start -0.7874 -0.4064)
			(end -0.7874 0.4064)
			(stroke
				(width 0.1524)
				(type default)
			)
			(layer "B.SilkS")
		)
		(fp_line
			(start 0.67945 0.3048)
			(end 0.67945 -0.305054)
			(stroke
				(width 0.1)
				(type default)
			)
			(layer "B.Fab")
		)
		(fp_line
			(start 0.67945 -0.305054)
			(end 0.12065 -0.305054)
			(stroke
				(width 0.1)
				(type default)
			)
			(layer "B.Fab")
		)
		(fp_line
			(start 0.12065 0.3048)
			(end 0.67945 0.3048)
			(stroke
				(width 0.1)
				(type default)
			)
			(layer "B.Fab")
		)
		(fp_line
			(start 0.12065 0.2794)
			(end 0.12065 0.3048)
			(stroke
				(width 0.1)
				(type default)
			)
			(layer "B.Fab")
		)
		(fp_line
			(start 0.12065 -0.2794)
			(end -0.12065 -0.2794)
			(stroke
				(width 0.1)
				(type default)
			)
			(layer "B.Fab")
		)
		(fp_line
			(start 0.12065 -0.305054)
			(end 0.12065 -0.2794)
			(stroke
				(width 0.1)
				(type default)
			)
			(layer "B.Fab")
		)
		(fp_line
			(start -0.120396 0.3048)
			(end -0.120396 0.2794)
			(stroke
				(width 0.1)
				(type default)
			)
			(layer "B.Fab")
		)
		(fp_line
			(start -0.120396 0.2794)
			(end 0.12065 0.2794)
			(stroke
				(width 0.1)
				(type default)
			)
			(layer "B.Fab")
		)
		(fp_line
			(start -0.12065 -0.2794)
			(end -0.12065 -0.3048)
			(stroke
				(width 0.1)
				(type default)
			)
			(layer "B.Fab")
		)
		(fp_line
			(start -0.12065 -0.3048)
			(end -0.67945 -0.3048)
			(stroke
				(width 0.1)
				(type default)
			)
			(layer "B.Fab")
		)
		(fp_line
			(start -0.67945 0.3048)
			(end -0.120396 0.3048)
			(stroke
				(width 0.1)
				(type default)
			)
			(layer "B.Fab")
		)
		(fp_line
			(start -0.67945 -0.3048)
			(end -0.67945 0.3048)
			(stroke
				(width 0.1)
				(type default)
			)
			(layer "B.Fab")
		)
		(pad "1" smd circle
			(at 0.40005 0)
			(size 0 0)
			(layers "B.Cu" "B.Mask" "B.Paste")
			(net "P3V3_NIC6")
		)
		(pad "2" smd circle
			(at -0.40005 0)
			(size 0 0)
			(layers "B.Cu" "B.Mask" "B.Paste")
			(net "GND")
		)
	)
	(footprint ""
		(layer "B.Cu")
		(at 398.925034 -297.79976 -90)
		(property "Reference" "C1905"
			(at 0 0 90)
			(layer "B.SilkS")
			(hide yes)
			(effects
				(font
					(size 1.27 1.27)
				)
				(justify mirror)
			)
		)
		(property "Value" ""
			(at 0 0 90)
			(layer "B.Fab")
			(effects
				(font
					(size 1.27 1.27)
				)
				(justify mirror)
			)
		)
		(duplicate_pad_numbers_are_jumpers no)
		(fp_line
			(start -0.299974 0.150114)
			(end 0.299974 0.150114)
			(stroke
				(width 0.1)
				(type default)
			)
			(layer "B.Fab")
		)
		(fp_line
			(start 0.299974 0.150114)
			(end 0.299974 -0.150114)
			(stroke
				(width 0.1)
				(type default)
			)
			(layer "B.Fab")
		)
		(fp_line
			(start -0.299974 -0.150114)
			(end -0.299974 0.150114)
			(stroke
				(width 0.1)
				(type default)
			)
			(layer "B.Fab")
		)
		(fp_line
			(start 0.299974 -0.150114)
			(end -0.299974 -0.150114)
			(stroke
				(width 0.1)
				(type default)
			)
			(layer "B.Fab")
		)
		(pad "1" smd rect
			(at 0.2667 0 90)
			(size 0.3048 0.381)
			(layers "B.Cu" "B.Mask" "B.Paste")
			(net "P0V8_PEX3")
		)
		(pad "2" smd rect
			(at -0.2667 0 90)
			(size 0.3048 0.381)
			(layers "B.Cu" "B.Mask" "B.Paste")
			(net "GND")
		)
	)
	(footprint ""
		(layer "B.Cu")
		(at 52.524914 -297.79976 -90)
		(property "Reference" "C1122"
			(at 0 0 90)
			(layer "B.SilkS")
			(hide yes)
			(effects
				(font
					(size 1.27 1.27)
				)
				(justify mirror)
			)
		)
		(property "Value" ""
			(at 0 0 90)
			(layer "B.Fab")
			(effects
				(font
					(size 1.27 1.27)
				)
				(justify mirror)
			)
		)
		(duplicate_pad_numbers_are_jumpers no)
		(fp_line
			(start -0.299974 0.150114)
			(end 0.299974 0.150114)
			(stroke
				(width 0.1)
				(type default)
			)
			(layer "B.Fab")
		)
		(fp_line
			(start 0.299974 0.150114)
			(end 0.299974 -0.150114)
			(stroke
				(width 0.1)
				(type default)
			)
			(layer "B.Fab")
		)
		(fp_line
			(start -0.299974 -0.150114)
			(end -0.299974 0.150114)
			(stroke
				(width 0.1)
				(type default)
			)
			(layer "B.Fab")
		)
		(fp_line
			(start 0.299974 -0.150114)
			(end -0.299974 -0.150114)
			(stroke
				(width 0.1)
				(type default)
			)
			(layer "B.Fab")
		)
		(pad "1" smd rect
			(at 0.2667 0 90)
			(size 0.3048 0.381)
			(layers "B.Cu" "B.Mask" "B.Paste")
			(net "P0V8_PEX0")
		)
		(pad "2" smd rect
			(at -0.2667 0 90)
			(size 0.3048 0.381)
			(layers "B.Cu" "B.Mask" "B.Paste")
			(net "GND")
		)
	)
)
